(kicad_pcb
	(version 20241229)
	(generator "pcbnew")
	(generator_version "9.0")
	(general
		(thickness 1.6642)
		(legacy_teardrops no)
	)
	(paper "A3")
	(title_block
		(title "PolarFire SoM")
		(date "2025-07-22")
		(rev "1.1.4")
		(company "Antmicro Ltd")
		(comment 1 "www.antmicro.com")
		(comment 9 "footprints 8-8 of 470")
	)
	(layers
		(0 "F.Cu" mixed)
		(4 "In1.Cu" power)
		(6 "In2.Cu" signal)
		(8 "In3.Cu" power)
		(10 "In4.Cu" signal)
		(12 "In5.Cu" power)
		(14 "In6.Cu" power)
		(16 "In7.Cu" signal)
		(18 "In8.Cu" power)
		(20 "In9.Cu" signal)
		(22 "In10.Cu" power)
		(24 "In11.Cu" signal)
		(26 "In12.Cu" signal)
		(2 "B.Cu" mixed)
		(9 "F.Adhes" user "F.Adhesive")
		(11 "B.Adhes" user "B.Adhesive")
		(13 "F.Paste" user)
		(15 "B.Paste" user)
		(5 "F.SilkS" user "F.Silkscreen")
		(7 "B.SilkS" user "B.Silkscreen")
		(1 "F.Mask" user)
		(3 "B.Mask" user)
		(17 "Dwgs.User" user "User.Drawings")
		(19 "Cmts.User" user "User.Comments")
		(21 "Eco1.User" user "User.Eco1")
		(23 "Eco2.User" user "User.Eco2")
		(25 "Edge.Cuts" user)
		(27 "Margin" user)
		(31 "F.CrtYd" user "F.Courtyard")
		(29 "B.CrtYd" user "B.Courtyard")
		(35 "F.Fab" user)
		(33 "B.Fab" user)
	)
	(footprint "antmicro-footprints:VQFN-48_7x7mm_P0.5mm_EP4.1x4.1mm"
		(layer "F.Cu")
		(at 216.8 120.4 180)
		(property "Reference" "U11"
			(at 4.2 -4.15 90)
			(unlocked yes)
			(layer "F.SilkS")
			(effects
				(font
					(size 0.7 0.7)
					(thickness 0.15)
				)
				(justify left bottom)
			)
		)
		(property "Value" "DP83867ISRGZR"
			(at 0 5.3 180)
			(unlocked yes)
			(layer "F.Fab")
			(hide yes)
			(effects
				(font
					(size 0.7 0.7)
					(thickness 0.15)
				)
				(justify left bottom)
			)
		)
		(property "Datasheet" "https://www.ti.com/lit/ds/symlink/dp83867is.pdf?HQS=dis-dk-null-digikeymode-dsf-pf-null-wwe&ts=1704962980288&ref_url=https%253A%252F%252Fwww.ti.com%252Fgeneral%252Fdocs%252Fsuppproductinfo.tsp%253FdistId%253D10%2526gotoUrl%253Dhttps%253A%252F%252Fwww.ti.com%252Flit%252Fgpn%252Fdp83867is"
			(at 0 0 180)
			(layer "F.Fab")
			(hide yes)
			(effects
				(font
					(size 1.27 1.27)
					(thickness 0.15)
				)
			)
		)
		(property "Description" "Robust, High Immunity, Small Form Factor 10/100/1000 Ethernet, Physical Layer Transceiver, SGMII/RGMII"
			(at 0 0 180)
			(layer "F.Fab")
			(hide yes)
			(effects
				(font
					(size 1.27 1.27)
					(thickness 0.15)
				)
			)
		)
		(property "Author" "Antmicro"
			(at 433.6 240.8 0)
			(layer "F.Fab")
			(hide yes)
			(effects
				(font
					(size 1 1)
					(thickness 0.15)
				)
			)
		)
		(property "License" "Apache-2.0"
			(at 433.6 240.8 0)
			(layer "F.Fab")
			(hide yes)
			(effects
				(font
					(size 1 1)
					(thickness 0.15)
				)
			)
		)
		(property "MPN" "DP83867ISRGZR"
			(at 433.6 240.8 0)
			(layer "F.Fab")
			(hide yes)
			(effects
				(font
					(size 1 1)
					(thickness 0.15)
				)
			)
		)
		(property "Manufacturer" "Texas Instruments"
			(at 433.6 240.8 0)
			(layer "F.Fab")
			(hide yes)
			(effects
				(font
					(size 1 1)
					(thickness 0.15)
				)
			)
		)
		(property ki_fp_filters "RGZ0048B RGZ0048B_NV")
		(sheetname "/Ethernet/")
		(sheetfile "ethernet.kicad_sch")
		(attr smd)
		(fp_line
			(start 3.956 3.956)
			(end 3.956 3.218)
			(stroke
				(width 0.15)
				(type solid)
			)
			(layer "F.SilkS")
		)
		(fp_line
			(start 3.956 3.956)
			(end 3.219 3.956)
			(stroke
				(width 0.15)
				(type solid)
			)
			(layer "F.SilkS")
		)
		(fp_line
			(start 3.956 -3.218)
			(end 3.956 -3.956)
			(stroke
				(width 0.15)
				(type solid)
			)
			(layer "F.SilkS")
		)
		(fp_line
			(start 3.956 -3.956)
			(end 3.219 -3.956)
			(stroke
				(width 0.15)
				(type solid)
			)
			(layer "F.SilkS")
		)
		(fp_line
			(start -3.219 3.956)
			(end -3.956 3.956)
			(stroke
				(width 0.15)
				(type solid)
			)
			(layer "F.SilkS")
		)
		(fp_line
			(start -3.219 -3.956)
			(end -3.956 -3.956)
			(stroke
				(width 0.15)
				(type solid)
			)
			(layer "F.SilkS")
		)
		(fp_line
			(start -3.956 3.956)
			(end -3.956 3.218)
			(stroke
				(width 0.15)
				(type solid)
			)
			(layer "F.SilkS")
		)
		(fp_line
			(start -3.956 -3.218)
			(end -3.956 -3.956)
			(stroke
				(width 0.15)
				(type solid)
			)
			(layer "F.SilkS")
		)
		(fp_circle
			(center -4.18 -3.05)
			(end -4.13 -3.05)
			(stroke
				(width 0.15)
				(type solid)
			)
			(fill yes)
			(layer "F.SilkS")
		)
		(fp_rect
			(start -4.3 -4.3)
			(end 4.3 4.3)
			(stroke
				(width 0.05)
				(type solid)
			)
			(fill no)
			(layer "F.CrtYd")
		)
		(fp_line
			(start 3.575 3.575)
			(end 3.575 -3.575)
			(stroke
				(width 0.15)
				(type solid)
			)
			(layer "B.Fab")
		)
		(fp_line
			(start 3.575 3.575)
			(end -3.575 3.575)
			(stroke
				(width 0.15)
				(type solid)
			)
			(layer "B.Fab")
		)
		(fp_line
			(start 3.575 -3.575)
			(end -3.575 -3.575)
			(stroke
				(width 0.15)
				(type solid)
			)
			(layer "B.Fab")
		)
		(fp_line
			(start -3.575 3.575)
			(end -3.575 -3.575)
			(stroke
				(width 0.15)
				(type solid)
			)
			(layer "B.Fab")
		)
		(fp_line
			(start -3.575 -2.305)
			(end -2.305 -3.575)
			(stroke
				(width 0.15)
				(type solid)
			)
			(layer "B.Fab")
		)
		(fp_text user "Author: Antmicro"
			(at -5.13 7.98 180)
			(layer "F.Fab")
			(effects
				(font
					(size 0.7 0.7)
					(thickness 0.15)
				)
				(justify left bottom)
			)
		)
		(fp_text user "License: Apache-2.0"
			(at -5.13 9.18 180)
			(layer "F.Fab")
			(effects
				(font
					(size 0.7 0.7)
					(thickness 0.15)
				)
				(justify left bottom)
			)
		)
		(fp_text user "${REFERENCE}"
			(at -5.13 6.78 180)
			(layer "F.Fab")
			(effects
				(font
					(size 0.7 0.7)
					(thickness 0.15)
				)
				(justify left bottom)
			)
		)
		(pad "1" smd roundrect
			(at -3.475 -2.75 90)
			(size 0.28 0.85)
			(layers "F.Cu" "F.Mask" "F.Paste")
			(roundrect_rratio 0.1785714286)
			(net 77 "/Ethernet/ETH.TXRX_A_P")
			(pinfunction "TD_P_A")
			(pintype "bidirectional")
		)
		(pad "2" smd roundrect
			(at -3.475 -2.25 90)
			(size 0.28 0.85)
			(layers "F.Cu" "F.Mask" "F.Paste")
			(roundrect_rratio 0.1785714286)
			(net 75 "/Ethernet/ETH.TXRX_A_N")
			(pinfunction "TD_M_A")
			(pintype "bidirectional")
		)
		(pad "3" smd roundrect
			(at -3.475 -1.75 90)
			(size 0.28 0.85)
			(layers "F.Cu" "F.Mask" "F.Paste")
			(roundrect_rratio 0.1785714286)
			(net 418 "+2V5")
			(pinfunction "VDDA2P5")
			(pintype "power_in")
		)
		(pad "4" smd roundrect
			(at -3.475 -1.25 90)
			(size 0.28 0.85)
			(layers "F.Cu" "F.Mask" "F.Paste")
			(roundrect_rratio 0.1785714286)
			(net 71 "/Ethernet/ETH.TXRX_B_P")
			(pinfunction "TD_P_B")
			(pintype "bidirectional")
		)
		(pad "5" smd roundrect
			(at -3.475 -0.75 90)
			(size 0.28 0.85)
			(layers "F.Cu" "F.Mask" "F.Paste")
			(roundrect_rratio 0.1785714286)
			(net 73 "/Ethernet/ETH.TXRX_B_N")
			(pinfunction "TD_M_B")
			(pintype "bidirectional")
		)
		(pad "6" smd roundrect
			(at -3.475 -0.25 90)
			(size 0.28 0.85)
			(layers "F.Cu" "F.Mask" "F.Paste")
			(roundrect_rratio 0.1785714286)
			(net 47 "+1V05")
			(pinfunction "VDD1P0")
			(pintype "passive")
		)
		(pad "7" smd roundrect
			(at -3.475 0.25 90)
			(size 0.28 0.85)
			(layers "F.Cu" "F.Mask" "F.Paste")
			(roundrect_rratio 0.1785714286)
			(net 76 "/Ethernet/ETH.TXRX_C_P")
			(pinfunction "TD_P_C")
			(pintype "bidirectional")
		)
		(pad "8" smd roundrect
			(at -3.475 0.75 90)
			(size 0.28 0.85)
			(layers "F.Cu" "F.Mask" "F.Paste")
			(roundrect_rratio 0.1785714286)
			(net 74 "/Ethernet/ETH.TXRX_C_N")
			(pinfunction "TD_M_C")
			(pintype "bidirectional")
		)
		(pad "9" smd roundrect
			(at -3.475 1.25 90)
			(size 0.28 0.85)
			(layers "F.Cu" "F.Mask" "F.Paste")
			(roundrect_rratio 0.1785714286)
			(net 418 "+2V5")
			(pinfunction "VDDA2P5")
			(pintype "passive")
		)
		(pad "10" smd roundrect
			(at -3.475 1.75 90)
			(size 0.28 0.85)
			(layers "F.Cu" "F.Mask" "F.Paste")
			(roundrect_rratio 0.1785714286)
			(net 70 "/Ethernet/ETH.TXRX_D_P")
			(pinfunction "TD_P_D")
			(pintype "bidirectional")
		)
		(pad "11" smd roundrect
			(at -3.475 2.25 90)
			(size 0.28 0.85)
			(layers "F.Cu" "F.Mask" "F.Paste")
			(roundrect_rratio 0.1785714286)
			(net 72 "/Ethernet/ETH.TXRX_D_N")
			(pinfunction "TD_M_D")
			(pintype "bidirectional")
		)
		(pad "12" smd roundrect
			(at -3.475 2.75 90)
			(size 0.28 0.85)
			(layers "F.Cu" "F.Mask" "F.Paste")
			(roundrect_rratio 0.1785714286)
			(net 222 "Net-(U11-RBIAS)")
			(pinfunction "RBIAS")
			(pintype "passive")
		)
		(pad "13" smd roundrect
			(at -2.75 3.475)
			(size 0.28 0.85)
			(layers "F.Cu" "F.Mask" "F.Paste")
			(roundrect_rratio 0.1785714286)
			(net 561 "unconnected-(U11-VDDA1P8-Pad13)")
			(pinfunction "VDDA1P8")
			(pintype "power_in+no_connect")
		)
		(pad "14" smd roundrect
			(at -2.25 3.475)
			(size 0.28 0.85)
			(layers "F.Cu" "F.Mask" "F.Paste")
			(roundrect_rratio 0.1785714286)
			(net 531 "unconnected-(U11-X_O-Pad14)")
			(pinfunction "X_O")
			(pintype "output+no_connect")
		)
		(pad "15" smd roundrect
			(at -1.75 3.475)
			(size 0.28 0.85)
			(layers "F.Cu" "F.Mask" "F.Paste")
			(roundrect_rratio 0.1785714286)
			(net 13 "/Ethernet/X_I")
			(pinfunction "X_I")
			(pintype "input")
		)
		(pad "16" smd roundrect
			(at -1.25 3.475)
			(size 0.28 0.85)
			(layers "F.Cu" "F.Mask" "F.Paste")
			(roundrect_rratio 0.1785714286)
			(net 618 "/Ethernet/ETH.MDC")
			(pinfunction "MDC")
			(pintype "input")
		)
		(pad "17" smd roundrect
			(at -0.75 3.475)
			(size 0.28 0.85)
			(layers "F.Cu" "F.Mask" "F.Paste")
			(roundrect_rratio 0.1785714286)
			(net 343 "/Ethernet/ETH.MDIO")
			(pinfunction "MDIO")
			(pintype "bidirectional")
		)
		(pad "18" smd roundrect
			(at -0.25 3.475)
			(size 0.28 0.85)
			(layers "F.Cu" "F.Mask" "F.Paste")
			(roundrect_rratio 0.1785714286)
			(net 532 "unconnected-(U11-CLK_OUT-Pad18)")
			(pinfunction "CLK_OUT")
			(pintype "output+no_connect")
		)
		(pad "19" smd roundrect
			(at 0.25 3.475)
			(size 0.28 0.85)
			(layers "F.Cu" "F.Mask" "F.Paste")
			(roundrect_rratio 0.1785714286)
			(net 50 "+3V3")
			(pinfunction "VDDIO")
			(pintype "power_in")
		)
		(pad "20" smd roundrect
			(at 0.75 3.475)
			(size 0.28 0.85)
			(layers "F.Cu" "F.Mask" "F.Paste")
			(roundrect_rratio 0.1785714286)
			(net 124 "JTAG_TCK")
			(pinfunction "JTAG_CLK")
			(pintype "input")
		)
		(pad "21" smd roundrect
			(at 1.25 3.475)
			(size 0.28 0.85)
			(layers "F.Cu" "F.Mask" "F.Paste")
			(roundrect_rratio 0.1785714286)
			(net 560 "Net-(U11-JTAG_TDO)")
			(pinfunction "JTAG_TDO")
			(pintype "output")
		)
		(pad "22" smd roundrect
			(at 1.75 3.475)
			(size 0.28 0.85)
			(layers "F.Cu" "F.Mask" "F.Paste")
			(roundrect_rratio 0.1785714286)
			(net 123 "JTAG_TMS")
			(pinfunction "JTAG_TMS")
			(pintype "input")
		)
		(pad "23" smd roundrect
			(at 2.25 3.475)
			(size 0.28 0.85)
			(layers "F.Cu" "F.Mask" "F.Paste")
			(roundrect_rratio 0.1785714286)
			(net 257 "WL_BT_TDO")
			(pinfunction "JTAG_TDI")
			(pintype "input")
		)
		(pad "24" smd roundrect
			(at 2.75 3.475)
			(size 0.28 0.85)
			(layers "F.Cu" "F.Mask" "F.Paste")
			(roundrect_rratio 0.1785714286)
			(net 47 "+1V05")
			(pinfunction "VDD1P0")
			(pintype "power_in")
		)
		(pad "25" smd roundrect
			(at 3.475 2.75 90)
			(size 0.28 0.85)
			(layers "F.Cu" "F.Mask" "F.Paste")
			(roundrect_rratio 0.1785714286)
			(net 227 "Net-(U11-GTX_CLK)")
			(pinfunction "TX_D3")
			(pintype "input")
		)
		(pad "26" smd roundrect
			(at 3.475 2.25 90)
			(size 0.28 0.85)
			(layers "F.Cu" "F.Mask" "F.Paste")
			(roundrect_rratio 0.1785714286)
			(net 227 "Net-(U11-GTX_CLK)")
			(pinfunction "TX_D2")
			(pintype "input")
		)
		(pad "27" smd roundrect
			(at 3.475 1.75 90)
			(size 0.28 0.85)
			(layers "F.Cu" "F.Mask" "F.Paste")
			(roundrect_rratio 0.1785714286)
			(net 164 "/Ethernet/SGMII_SI_P")
			(pinfunction "TX_D1/SGMII_SIP")
			(pintype "input")
		)
		(pad "28" smd roundrect
			(at 3.475 1.25 90)
			(size 0.28 0.85)
			(layers "F.Cu" "F.Mask" "F.Paste")
			(roundrect_rratio 0.1785714286)
			(net 167 "/Ethernet/SGMII_SI_N")
			(pinfunction "TX_D0/SGMII_SIN")
			(pintype "input")
		)
		(pad "29" smd roundrect
			(at 3.475 0.75 90)
			(size 0.28 0.85)
			(layers "F.Cu" "F.Mask" "F.Paste")
			(roundrect_rratio 0.1785714286)
			(net 227 "Net-(U11-GTX_CLK)")
			(pinfunction "GTX_CLK")
			(pintype "input")
		)
		(pad "30" smd roundrect
			(at 3.475 0.25 90)
			(size 0.28 0.85)
			(layers "F.Cu" "F.Mask" "F.Paste")
			(roundrect_rratio 0.1785714286)
			(net 50 "+3V3")
			(pinfunction "VDDIO")
			(pintype "passive")
		)
		(pad "31" smd roundrect
			(at 3.475 -0.25 90)
			(size 0.28 0.85)
			(layers "F.Cu" "F.Mask" "F.Paste")
			(roundrect_rratio 0.1785714286)
			(net 47 "+1V05")
			(pinfunction "VDD1P0")
			(pintype "passive")
		)
		(pad "32" smd roundrect
			(at 3.475 -0.75 90)
			(size 0.28 0.85)
			(layers "F.Cu" "F.Mask" "F.Paste")
			(roundrect_rratio 0.1785714286)
			(net 533 "unconnected-(U11-RX_CLK-Pad32)")
			(pinfunction "RX_CLK")
			(pintype "output+no_connect")
		)
		(pad "33" smd roundrect
			(at 3.475 -1.25 90)
			(size 0.28 0.85)
			(layers "F.Cu" "F.Mask" "F.Paste")
			(roundrect_rratio 0.1785714286)
			(net 169 "/Ethernet/SGMII_CO_P")
			(pinfunction "RX_D0/SGMII_COP")
			(pintype "output")
		)
		(pad "34" smd roundrect
			(at 3.475 -1.75 90)
			(size 0.28 0.85)
			(layers "F.Cu" "F.Mask" "F.Paste")
			(roundrect_rratio 0.1785714286)
			(net 165 "/Ethernet/SGMII_CO_N")
			(pinfunction "RX_D1/SGMII_CON")
			(pintype "output")
		)
		(pad "35" smd roundrect
			(at 3.475 -2.25 90)
			(size 0.28 0.85)
			(layers "F.Cu" "F.Mask" "F.Paste")
			(roundrect_rratio 0.1785714286)
			(net 170 "/Ethernet/SGMII_SO_P")
			(pinfunction "RX_D2/SGMII_SOP")
			(pintype "output")
		)
		(pad "36" smd roundrect
			(at 3.475 -2.75 90)
			(size 0.28 0.85)
			(layers "F.Cu" "F.Mask" "F.Paste")
			(roundrect_rratio 0.1785714286)
			(net 166 "/Ethernet/SGMII_SO_N")
			(pinfunction "RX_D3/SGMII_SON")
			(pintype "output")
		)
		(pad "37" smd roundrect
			(at 2.75 -3.475)
			(size 0.28 0.85)
			(layers "F.Cu" "F.Mask" "F.Paste")
			(roundrect_rratio 0.1785714286)
			(net 227 "Net-(U11-GTX_CLK)")
			(pinfunction "TX_CTRL")
			(pintype "input")
		)
		(pad "38" smd roundrect
			(at 2.25 -3.475)
			(size 0.28 0.85)
			(layers "F.Cu" "F.Mask" "F.Paste")
			(roundrect_rratio 0.1785714286)
			(net 282 "/Ethernet/ETH_RXCTRL")
			(pinfunction "RX_CTRL")
			(pintype "output")
		)
		(pad "39" smd roundrect
			(at 1.75 -3.475)
			(size 0.28 0.85)
			(layers "F.Cu" "F.Mask" "F.Paste")
			(roundrect_rratio 0.1785714286)
			(net 79 "/Ethernet/ETH.SYNC_IN")
			(pinfunction "GPIO_0")
			(pintype "output")
		)
		(pad "40" smd roundrect
			(at 1.25 -3.475)
			(size 0.28 0.85)
			(layers "F.Cu" "F.Mask" "F.Paste")
			(roundrect_rratio 0.1785714286)
			(net 81 "/Ethernet/ETH.SYNC_OUT")
			(pinfunction "GPIO_1")
			(pintype "output")
		)
		(pad "41" smd roundrect
			(at 0.75 -3.475)
			(size 0.28 0.85)
			(layers "F.Cu" "F.Mask" "F.Paste")
			(roundrect_rratio 0.1785714286)
			(net 50 "+3V3")
			(pinfunction "VDDIO")
			(pintype "passive")
		)
		(pad "42" smd roundrect
			(at 0.25 -3.475)
			(size 0.28 0.85)
			(layers "F.Cu" "F.Mask" "F.Paste")
			(roundrect_rratio 0.1785714286)
			(net 47 "+1V05")
			(pinfunction "VDD1P0")
			(pintype "passive")
		)
		(pad "43" smd roundrect
			(at -0.25 -3.475)
			(size 0.28 0.85)
			(layers "F.Cu" "F.Mask" "F.Paste")
			(roundrect_rratio 0.1785714286)
			(net 253 "ETH_RESET_n")
			(pinfunction "~{RESET}")
			(pintype "input")
		)
		(pad "44" smd roundrect
			(at -0.75 -3.475)
			(size 0.28 0.85)
			(layers "F.Cu" "F.Mask" "F.Paste")
			(roundrect_rratio 0.1785714286)
			(net 217 "ETH_PWDN_n")
			(pinfunction "~{INT}/~{PWDN}")
			(pintype "bidirectional")
		)
		(pad "45" smd roundrect
			(at -1.25 -3.475)
			(size 0.28 0.85)
			(layers "F.Cu" "F.Mask" "F.Paste")
			(roundrect_rratio 0.1785714286)
			(net 78 "/Ethernet/ETH.LED2")
			(pinfunction "LED_2")
			(pintype "bidirectional")
		)
		(pad "46" smd roundrect
			(at -1.75 -3.475)
			(size 0.28 0.85)
			(layers "F.Cu" "F.Mask" "F.Paste")
			(roundrect_rratio 0.1785714286)
			(net 80 "/Ethernet/ETH.LED1")
			(pinfunction "LED_1")
			(pintype "bidirectional")
		)
		(pad "47" smd roundrect
			(at -2.25 -3.475)
			(size 0.28 0.85)
			(layers "F.Cu" "F.Mask" "F.Paste")
			(roundrect_rratio 0.1785714286)
			(net 617 "/Ethernet/LED0")
			(pinfunction "LED_0")
			(pintype "bidirectional")
		)
		(pad "48" smd roundrect
			(at -2.75 -3.475)
			(size 0.28 0.85)
			(layers "F.Cu" "F.Mask" "F.Paste")
			(roundrect_rratio 0.1785714286)
			(net 652 "unconnected-(U11-VDDA1P8-Pad13)_1")
			(pinfunction "VDDA1P8")
			(pintype "passive+no_connect")
		)
		(pad "49" smd roundrect
			(at 0 0 180)
			(size 4.1 4.1)
			(layers "F.Cu" "F.Mask" "F.Paste")
			(roundrect_rratio 0.01219512195)
			(net 417 "GND")
			(pinfunction "GND")
			(pintype "power_in")
			(solder_paste_margin_ratio -0.1)
		)
	)
)
